#ISCELL
  mstr_misc dns *
  *
#ISCELL
  pure_quanta quanta_title_block_c *
  *
#CELL
  pure_quanta sn74avc4t774pwr *
  page141_i117
#ISCELL
  pure_quanta_power universal_power *
  page141_i120
#ISCELL
  standard offpage *
  page141_i126
#ISCELL
  pure_quanta_power universal_power *
  page141_i128
#CELL
  pure_quanta q_cap *
  page141_i133
#ISCELL
  pure_quanta_power universal_gnd *
  page141_i134
#ISCELL
  pure_quanta_power universal_power *
  page141_i135
#ISCELL
  pure_quanta_power universal_gnd *
  page141_i136
#CELL
  pure_quanta q_cap *
  page141_i137
#ISCELL
  standard offpage *
  page141_i138
#ISCELL
  pure_quanta_power universal_power *
  page141_i145
#ISCELL
  pure_quanta_power universal_power *
  page141_i148
#ISCELL
  pure_quanta_power universal_gnd *
  page141_i180
#ISCELL
  pure_quanta_power universal_power *
  page141_i181
#ISCELL
  pure_quanta_power p1v0 *
  page141_i182
#ISCELL
  standard offpage *
  page141_i184
#CELL
  pure_quanta q_res *
  page141_i185
#CELL
  pure_quanta q_res *
  page141_i186
#CELL
  pure_quanta q_cap *
  page141_i187
#ISCELL
  pure_quanta_power universal_gnd *
  page141_i188
#ISCELL
  pure_quanta_power universal_gnd *
  page141_i189
#CELL
  pure_quanta q_cap *
  page141_i190
#CELL
  pure_quanta conn4_hfk1040l0p1l7h *
  page141_i195
#CELL
  pure_quanta q_res *
  page141_i196
#CELL
  pure_quanta q_res *
  page141_i197
#CELL
  pure_quanta q_res *
  page141_i198
#CELL
  pure_quanta q_res *
  page141_i199
#ISCELL
  standard offpage *
  page141_i200
#ISCELL
  standard offpage *
  page141_i201
#ISCELL
  standard offpage *
  page141_i202
#CELL
  pure_quanta q_res *
  page141_i203
#CELL
  pure_quanta q_res *
  page141_i204
#CELL
  pure_quanta q_res *
  page141_i205
#CELL
  pure_quanta q_res *
  page141_i206
#ISCELL
  standard offpage *
  page141_i207
#ISCELL
  standard offpage *
  page141_i208
#ISCELL
  standard offpage *
  page141_i209
#ISCELL
  standard offpage *
  page141_i210
#CELL
  pure_quanta q_res *
  page141_i211
#CELL
  pure_quanta q_res *
  page141_i212
#ISCELL
  standard offpage *
  page141_i213
#CELL
  pure_quanta q_res *
  page141_i220
#CELL
  pure_quanta q_res *
  page141_i221
#ISCELL
  standard offpage *
  page141_i222
#ISCELL
  standard offpage *
  page141_i223
#ISCELL
  standard offpage *
  page141_i224
#ISCELL
  standard offpage *
  page141_i225
#ISCELL
  pure_quanta_power universal_gnd *
  page141_i226
#ISCELL
  standard offpage *
  page141_i227
#ISCELL
  standard offpage *
  page141_i228
#ISCELL
  standard offpage *
  page141_i229
#ISCELL
  standard offpage *
  page141_i230
#CELL
  pure_quanta q_res *
  page141_i231
#CELL
  pure_quanta q_res *
  page141_i232
#ISCELL
  standard offpage *
  page141_i233
#ISCELL
  pure_quanta_power universal_gnd *
  page141_i234
#ISCELL
  pure_quanta_power universal_gnd *
  page141_i235
#ISCELL
  pure_quanta_power universal_power *
  page141_i236
#ISCELL
  standard offpage *
  page141_i88
#CELL
  pure_quanta mosfet_n_gsd *
  page141_i89
#ISCELL
  pure_quanta_power universal_gnd *
  page141_i90
#CELL
  pure_quanta q_res *
  page141_i91
